(kicad_pcb
	(version 20260206)
	(generator "pcbnew")
	(generator_version "10.0")
	(general
		(thickness 1.6)
		(legacy_teardrops no)
	)
	(paper "A4")
	(title_block
		(title "baseboard — 13948-1b.1110WZS1818.brd")
		(comment 1 "Honey Badger (Wiwynn) / footprints 411-418 of 2523")
	)
	(layers
		(0 "F.Cu" signal "TOP")
		(4 "In1.Cu" signal "L2GND")
		(6 "In2.Cu" signal "L3")
		(8 "In3.Cu" signal "L4VCC")
		(10 "In4.Cu" signal "L5VCC")
		(12 "In5.Cu" signal "L6")
		(14 "In6.Cu" signal "L7GND")
		(2 "B.Cu" signal "BOTTOM")
		(9 "F.Adhes" user "F.Adhesive")
		(11 "B.Adhes" user "B.Adhesive")
		(13 "F.Paste" user "Package Geometry/Pastemask Top")
		(15 "B.Paste" user "Package Geometry/Pastemask Bottom")
		(5 "F.SilkS" user "Ref Des/Silkscreen Top")
		(7 "B.SilkS" user "Ref Des/Silkscreen Bottom")
		(1 "F.Mask" user "Board Geometry/Soldermask Top")
		(3 "B.Mask" user "Board Geometry/Soldermask Bottom")
		(17 "Dwgs.User" user "User.Drawings")
		(19 "Cmts.User" user "User.Comments")
		(21 "Eco1.User" user "User.Eco1")
		(23 "Eco2.User" user "User.Eco2")
		(25 "Edge.Cuts" user "Board Geometry/Outline")
		(27 "Margin" user)
		(31 "F.CrtYd" user "Package Geometry/Place Bound Top")
		(29 "B.CrtYd" user "Package Geometry/Place Bound Bottom")
		(35 "F.Fab" user "Ref Des/Assembly Top")
		(33 "B.Fab" user "Ref Des/Assembly Bottom")
	)
	(footprint ""
		(layer "F.Cu")
		(at 326.009 -143.383 90)
		(property "Reference" "C307"
			(at 0 0 90)
			(layer "F.SilkS")
			(hide yes)
			(effects
				(font
					(size 1.27 1.27)
				)
			)
		)
		(property "Value" "SC15P50V2JN-2-GP"
			(at 1.1811 -2.7051 90)
			(unlocked yes)
			(layer "F.Fab")
			(hide yes)
			(effects
				(font
					(size 1.016 1.016)
					(thickness 0.1524)
				)
			)
		)
		(property "Device Type" "C402H22"
			(at 1.1811 -4.2291 90)
			(unlocked yes)
			(layer "F.Fab")
			(hide yes)
			(effects
				(font
					(size 1.016 1.016)
					(thickness 0.1524)
				)
			)
		)
		(duplicate_pad_numbers_are_jumpers no)
		(fp_rect
			(start -0.4318 0.9525)
			(end 0.4318 -0.9525)
			(stroke
				(width 0)
				(type default)
			)
			(fill no)
			(layer "F.CrtYd")
		)
		(fp_rect
			(start -0.4318 0.9525)
			(end 0.4318 -0.9525)
			(stroke
				(width 0)
				(type default)
			)
			(fill no)
			(layer "F.Fab")
		)
		(pad "1" smd custom
			(at 0 -0.4445 90)
			(size 0.1524 0.1524)
			(layers "F.Cu" "F.Mask" "F.Paste")
			(net "RTC_OSCO")
			(options
				(clearance outline)
				(anchor circle)
			)
			(primitives
				(gr_poly
					(pts
						(arc
							(start 0.3048 -0.2032)
							(mid 0.275042 -0.275042)
							(end 0.2032 -0.3048)
						)
						(arc
							(start -0.2032 -0.3048)
							(mid -0.275042 -0.275042)
							(end -0.3048 -0.2032)
						)
						(arc
							(start -0.3048 0.2032)
							(mid -0.275042 0.275042)
							(end -0.2032 0.3048)
						)
						(arc
							(start 0.2032 0.3048)
							(mid 0.275042 0.275042)
							(end 0.3048 0.2032)
						)
					)
					(width 0)
					(fill yes)
				)
			)
		)
		(pad "2" smd custom
			(at 0 0.4445 90)
			(size 0.1524 0.1524)
			(layers "F.Cu" "F.Mask" "F.Paste")
			(net "GND")
			(options
				(clearance outline)
				(anchor circle)
			)
			(primitives
				(gr_poly
					(pts
						(arc
							(start 0.3048 -0.2032)
							(mid 0.275042 -0.275042)
							(end 0.2032 -0.3048)
						)
						(arc
							(start -0.2032 -0.3048)
							(mid -0.275042 -0.275042)
							(end -0.3048 -0.2032)
						)
						(arc
							(start -0.3048 0.2032)
							(mid -0.275042 0.275042)
							(end -0.2032 0.3048)
						)
						(arc
							(start 0.2032 0.3048)
							(mid 0.275042 0.275042)
							(end 0.3048 0.2032)
						)
					)
					(width 0)
					(fill yes)
				)
			)
		)
	)
	(footprint ""
		(layer "F.Cu")
		(at 266.7 -170.053)
		(property "Reference" "TP87"
			(at 0 0 0)
			(layer "F.SilkS")
			(hide yes)
			(effects
				(font
					(size 1.27 1.27)
				)
			)
		)
		(property "Value" "TPAD28"
			(at 0.0127 -1.8034 0)
			(unlocked yes)
			(layer "F.Fab")
			(hide yes)
			(effects
				(font
					(size 1.016 1.016)
					(thickness 0.1524)
				)
			)
		)
		(property "Device Type" "TPAD28"
			(at 0.0127 -3.3274 0)
			(unlocked yes)
			(layer "F.Fab")
			(hide yes)
			(effects
				(font
					(size 1.016 1.016)
					(thickness 0.1524)
				)
			)
		)
		(duplicate_pad_numbers_are_jumpers no)
		(fp_poly
			(pts
				(arc
					(start 0.3556 0)
					(mid -0.3556 0)
					(end 0.3556 0)
				)
			)
			(stroke
				(width 0)
				(type default)
			)
			(fill no)
			(layer "F.CrtYd")
		)
		(fp_poly
			(pts
				(arc
					(start 0.6096 0)
					(mid -0.6096 0)
					(end 0.6096 0)
				)
			)
			(stroke
				(width 0)
				(type default)
			)
			(fill no)
			(layer "F.Fab")
		)
		(pad "1" smd circle
			(at 0 0)
			(size 0.7112 0.7112)
			(layers "F.Cu" "F.Mask" "F.Paste")
			(net "BMC_MBC_I2C_E_SDA")
		)
	)
	(footprint ""
		(layer "F.Cu")
		(at 208.153 -216.789 90)
		(property "Reference" "R443"
			(at 0 0 90)
			(layer "F.SilkS")
			(hide yes)
			(effects
				(font
					(size 1.27 1.27)
				)
			)
		)
		(property "Value" "10KR2F-2-GP"
			(at 0.064008 -3.993896 90)
			(unlocked yes)
			(layer "F.Fab")
			(hide yes)
			(effects
				(font
					(size 1.016 1.016)
					(thickness 0.1524)
				)
			)
		)
		(property "Device Type" "R402H16"
			(at 0.064008 -5.517896 90)
			(unlocked yes)
			(layer "F.Fab")
			(hide yes)
			(effects
				(font
					(size 1.016 1.016)
					(thickness 0.1524)
				)
			)
		)
		(duplicate_pad_numbers_are_jumpers no)
		(fp_line
			(start 0.508 -0.9398)
			(end -0.508 -0.9398)
			(stroke
				(width 0.1524)
				(type default)
			)
			(layer "F.SilkS")
		)
		(fp_line
			(start -0.508 -0.9398)
			(end -0.508 0.9398)
			(stroke
				(width 0.1524)
				(type default)
			)
			(layer "F.SilkS")
		)
		(fp_rect
			(start -0.508 0.9398)
			(end 0.508 -0.9398)
			(stroke
				(width 0)
				(type default)
			)
			(fill no)
			(layer "F.CrtYd")
		)
		(fp_rect
			(start -0.508 0.9398)
			(end 0.508 -0.9398)
			(stroke
				(width 0)
				(type default)
			)
			(fill no)
			(layer "F.Fab")
		)
		(pad "1" smd custom
			(at 0 -0.4445 90)
			(size 0.1397 0.1397)
			(layers "F.Cu" "F.Mask" "F.Paste")
			(net "P3V3_STBY")
			(options
				(clearance outline)
				(anchor circle)
			)
			(primitives
				(gr_poly
					(pts
						(arc
							(start -0.1778 -0.2794)
							(mid -0.249642 -0.249642)
							(end -0.2794 -0.1778)
						)
						(arc
							(start -0.2794 0.1778)
							(mid -0.249642 0.249642)
							(end -0.1778 0.2794)
						)
						(arc
							(start 0.1778 0.2794)
							(mid 0.249642 0.249642)
							(end 0.2794 0.1778)
						)
						(arc
							(start 0.2794 -0.1778)
							(mid 0.249642 -0.249642)
							(end 0.1778 -0.2794)
						)
					)
					(width 0)
					(fill yes)
				)
			)
		)
		(pad "2" smd custom
			(at 0 0.4445 90)
			(size 0.1397 0.1397)
			(layers "F.Cu" "F.Mask" "F.Paste")
			(net "DP_BMC_CPU_RST_N")
			(options
				(clearance outline)
				(anchor circle)
			)
			(primitives
				(gr_poly
					(pts
						(arc
							(start -0.1778 -0.2794)
							(mid -0.249642 -0.249642)
							(end -0.2794 -0.1778)
						)
						(arc
							(start -0.2794 0.1778)
							(mid -0.249642 0.249642)
							(end -0.1778 0.2794)
						)
						(arc
							(start 0.1778 0.2794)
							(mid 0.249642 0.249642)
							(end 0.2794 0.1778)
						)
						(arc
							(start 0.2794 -0.1778)
							(mid 0.249642 -0.249642)
							(end 0.1778 -0.2794)
						)
					)
					(width 0)
					(fill yes)
				)
			)
		)
	)
	(footprint ""
		(layer "F.Cu")
		(at 36.449 -178.943 180)
		(property "Reference" "SR1276"
			(at 0 0 180)
			(layer "F.SilkS")
			(hide yes)
			(effects
				(font
					(size 1.27 1.27)
				)
			)
		)
		(property "Value" "1KR2J-1-GP"
			(at 0.064008 -3.993896 180)
			(unlocked yes)
			(layer "F.Fab")
			(hide yes)
			(effects
				(font
					(size 1.016 1.016)
					(thickness 0.1524)
				)
			)
		)
		(property "Device Type" "R402H16"
			(at 0.064008 -5.517896 180)
			(unlocked yes)
			(layer "F.Fab")
			(hide yes)
			(effects
				(font
					(size 1.016 1.016)
					(thickness 0.1524)
				)
			)
		)
		(duplicate_pad_numbers_are_jumpers no)
		(fp_line
			(start 0.508 -0.9398)
			(end -0.508 -0.9398)
			(stroke
				(width 0.1524)
				(type default)
			)
			(layer "F.SilkS")
		)
		(fp_line
			(start -0.508 -0.9398)
			(end -0.508 0.9398)
			(stroke
				(width 0.1524)
				(type default)
			)
			(layer "F.SilkS")
		)
		(fp_rect
			(start -0.508 0.9398)
			(end 0.508 -0.9398)
			(stroke
				(width 0)
				(type default)
			)
			(fill no)
			(layer "F.CrtYd")
		)
		(fp_rect
			(start -0.508 0.9398)
			(end 0.508 -0.9398)
			(stroke
				(width 0)
				(type default)
			)
			(fill no)
			(layer "F.Fab")
		)
		(pad "1" smd custom
			(at 0 -0.4445 180)
			(size 0.1397 0.1397)
			(layers "F.Cu" "F.Mask" "F.Paste")
			(net "DP_EXP_RST_R")
			(options
				(clearance outline)
				(anchor circle)
			)
			(primitives
				(gr_poly
					(pts
						(arc
							(start -0.1778 -0.2794)
							(mid -0.249642 -0.249642)
							(end -0.2794 -0.1778)
						)
						(arc
							(start -0.2794 0.1778)
							(mid -0.249642 0.249642)
							(end -0.1778 0.2794)
						)
						(arc
							(start 0.1778 0.2794)
							(mid 0.249642 0.249642)
							(end 0.2794 0.1778)
						)
						(arc
							(start 0.2794 -0.1778)
							(mid 0.249642 -0.249642)
							(end 0.1778 -0.2794)
						)
					)
					(width 0)
					(fill yes)
				)
			)
		)
		(pad "2" smd custom
			(at 0 0.4445 180)
			(size 0.1397 0.1397)
			(layers "F.Cu" "F.Mask" "F.Paste")
			(net "P1V8_E")
			(options
				(clearance outline)
				(anchor circle)
			)
			(primitives
				(gr_poly
					(pts
						(arc
							(start -0.1778 -0.2794)
							(mid -0.249642 -0.249642)
							(end -0.2794 -0.1778)
						)
						(arc
							(start -0.2794 0.1778)
							(mid -0.249642 0.249642)
							(end -0.1778 0.2794)
						)
						(arc
							(start 0.1778 0.2794)
							(mid 0.249642 0.249642)
							(end 0.2794 0.1778)
						)
						(arc
							(start 0.2794 -0.1778)
							(mid 0.249642 -0.249642)
							(end 0.1778 -0.2794)
						)
					)
					(width 0)
					(fill yes)
				)
			)
		)
	)
	(footprint ""
		(layer "F.Cu")
		(at 299.847 -211.201 180)
		(property "Reference" "PR78"
			(at 0 0 180)
			(layer "F.SilkS")
			(hide yes)
			(effects
				(font
					(size 1.27 1.27)
				)
			)
		)
		(property "Value" "0R6J-3-GP"
			(at -0.0508 -4.8514 180)
			(unlocked yes)
			(layer "F.Fab")
			(hide yes)
			(effects
				(font
					(size 1.016 1.016)
					(thickness 0.1524)
				)
			)
		)
		(property "Device Type" "R1206H28"
			(at 0 -6.3754 180)
			(unlocked yes)
			(layer "F.Fab")
			(hide yes)
			(effects
				(font
					(size 1.016 1.016)
					(thickness 0.1524)
				)
			)
		)
		(duplicate_pad_numbers_are_jumpers no)
		(fp_line
			(start 1.016 2.2352)
			(end -1.016 2.2352)
			(stroke
				(width 0.1524)
				(type default)
			)
			(layer "F.SilkS")
		)
		(fp_line
			(start 1.016 -2.2352)
			(end 1.016 2.2352)
			(stroke
				(width 0.1524)
				(type default)
			)
			(layer "F.SilkS")
		)
		(fp_line
			(start -1.016 2.2352)
			(end -1.016 -2.2352)
			(stroke
				(width 0.1524)
				(type default)
			)
			(layer "F.SilkS")
		)
		(fp_line
			(start -1.016 -2.2352)
			(end 1.016 -2.2352)
			(stroke
				(width 0.1524)
				(type default)
			)
			(layer "F.SilkS")
		)
		(fp_rect
			(start -1.0922 2.3114)
			(end 1.0922 -2.3114)
			(stroke
				(width 0)
				(type default)
			)
			(fill no)
			(layer "F.CrtYd")
		)
		(fp_poly
			(pts
				(xy -1.0922 -2.3114) (xy 1.0922 -2.3114) (xy 1.0922 2.3114) (xy -1.0922 2.3114)
			)
			(stroke
				(width 0)
				(type default)
			)
			(fill no)
			(layer "F.Fab")
		)
		(pad "1" smd rect
			(at 0 -1.397 180)
			(size 1.651 1.27)
			(layers "F.Cu" "F.Mask" "F.Paste")
			(net "P1V53_STBY")
		)
		(pad "2" smd rect
			(at 0 1.397 180)
			(size 1.651 1.27)
			(layers "F.Cu" "F.Mask" "F.Paste")
			(net "TPS74801_1V53_STBY_OUT")
		)
	)
	(footprint ""
		(layer "F.Cu")
		(at 189.865 -24.003 90)
		(property "Reference" "R375"
			(at 0 0 90)
			(layer "F.SilkS")
			(hide yes)
			(effects
				(font
					(size 1.27 1.27)
				)
			)
		)
		(property "Value" "33R2J-2-GP"
			(at 0.064008 -3.993896 90)
			(unlocked yes)
			(layer "F.Fab")
			(hide yes)
			(effects
				(font
					(size 1.016 1.016)
					(thickness 0.1524)
				)
			)
		)
		(property "Device Type" "R402H16"
			(at 0.064008 -5.517896 90)
			(unlocked yes)
			(layer "F.Fab")
			(hide yes)
			(effects
				(font
					(size 1.016 1.016)
					(thickness 0.1524)
				)
			)
		)
		(duplicate_pad_numbers_are_jumpers no)
		(fp_line
			(start 0.508 -0.9398)
			(end -0.508 -0.9398)
			(stroke
				(width 0.1524)
				(type default)
			)
			(layer "F.SilkS")
		)
		(fp_line
			(start -0.508 -0.9398)
			(end -0.508 0.9398)
			(stroke
				(width 0.1524)
				(type default)
			)
			(layer "F.SilkS")
		)
		(fp_rect
			(start -0.508 0.9398)
			(end 0.508 -0.9398)
			(stroke
				(width 0)
				(type default)
			)
			(fill no)
			(layer "F.CrtYd")
		)
		(fp_rect
			(start -0.508 0.9398)
			(end 0.508 -0.9398)
			(stroke
				(width 0)
				(type default)
			)
			(fill no)
			(layer "F.Fab")
		)
		(pad "1" smd custom
			(at 0 -0.4445 90)
			(size 0.1397 0.1397)
			(layers "F.Cu" "F.Mask" "F.Paste")
			(net "RMII_PHY_BMC_RXD1_R")
			(options
				(clearance outline)
				(anchor circle)
			)
			(primitives
				(gr_poly
					(pts
						(arc
							(start -0.1778 -0.2794)
							(mid -0.249642 -0.249642)
							(end -0.2794 -0.1778)
						)
						(arc
							(start -0.2794 0.1778)
							(mid -0.249642 0.249642)
							(end -0.1778 0.2794)
						)
						(arc
							(start 0.1778 0.2794)
							(mid 0.249642 0.249642)
							(end 0.2794 0.1778)
						)
						(arc
							(start 0.2794 -0.1778)
							(mid 0.249642 -0.249642)
							(end 0.1778 -0.2794)
						)
					)
					(width 0)
					(fill yes)
				)
			)
		)
		(pad "2" smd custom
			(at 0 0.4445 90)
			(size 0.1397 0.1397)
			(layers "F.Cu" "F.Mask" "F.Paste")
			(net "RMII_PHY_BMC_RXD1")
			(options
				(clearance outline)
				(anchor circle)
			)
			(primitives
				(gr_poly
					(pts
						(arc
							(start -0.1778 -0.2794)
							(mid -0.249642 -0.249642)
							(end -0.2794 -0.1778)
						)
						(arc
							(start -0.2794 0.1778)
							(mid -0.249642 0.249642)
							(end -0.1778 0.2794)
						)
						(arc
							(start 0.1778 0.2794)
							(mid 0.249642 0.249642)
							(end 0.2794 0.1778)
						)
						(arc
							(start 0.2794 -0.1778)
							(mid 0.249642 -0.249642)
							(end 0.1778 -0.2794)
						)
					)
					(width 0)
					(fill yes)
				)
			)
		)
	)
	(footprint ""
		(layer "F.Cu")
		(at 205.486 -86.614)
		(property "Reference" "SR827"
			(at 0 0 0)
			(layer "F.SilkS")
			(hide yes)
			(effects
				(font
					(size 1.27 1.27)
				)
			)
		)
		(property "Value" "D51R3F-2-GP"
			(at -0.0254 -2.5146 0)
			(unlocked yes)
			(layer "F.Fab")
			(hide yes)
			(effects
				(font
					(size 1.016 1.016)
					(thickness 0.1524)
				)
			)
		)
		(property "Device Type" "R603H22"
			(at -0.0254 -4.0386 0)
			(unlocked yes)
			(layer "F.Fab")
			(hide yes)
			(effects
				(font
					(size 1.016 1.016)
					(thickness 0.1524)
				)
			)
		)
		(duplicate_pad_numbers_are_jumpers no)
		(fp_line
			(start -0.4826 0)
			(end -0.2032 0)
			(stroke
				(width 0.2032)
				(type default)
			)
			(layer "F.SilkS")
		)
		(fp_line
			(start 0.2032 0)
			(end 0.4826 0)
			(stroke
				(width 0.2032)
				(type default)
			)
			(layer "F.SilkS")
		)
		(fp_rect
			(start -0.5842 1.3335)
			(end 0.5842 -1.3335)
			(stroke
				(width 0)
				(type default)
			)
			(fill no)
			(layer "F.CrtYd")
		)
		(fp_rect
			(start -0.5842 1.3335)
			(end 0.5842 -1.3335)
			(stroke
				(width 0)
				(type default)
			)
			(fill no)
			(layer "F.Fab")
		)
		(pad "1" smd custom
			(at 0 -0.762)
			(size 0.2159 0.2159)
			(layers "F.Cu" "F.Mask" "F.Paste")
			(net "P1V5_E")
			(options
				(clearance outline)
				(anchor circle)
			)
			(primitives
				(gr_poly
					(pts
						(arc
							(start -0.3302 -0.4318)
							(mid -0.402042 -0.402042)
							(end -0.4318 -0.3302)
						)
						(arc
							(start -0.4318 0.3302)
							(mid -0.402042 0.402042)
							(end -0.3302 0.4318)
						)
						(arc
							(start 0.3302 0.4318)
							(mid 0.402042 0.402042)
							(end 0.4318 0.3302)
						)
						(arc
							(start 0.4318 -0.3302)
							(mid 0.402042 -0.402042)
							(end 0.3302 -0.4318)
						)
					)
					(width 0)
					(fill yes)
				)
			)
		)
		(pad "2" smd custom
			(at 0 0.762)
			(size 0.2159 0.2159)
			(layers "F.Cu" "F.Mask" "F.Paste")
			(net "GB_VDDH2")
			(options
				(clearance outline)
				(anchor circle)
			)
			(primitives
				(gr_poly
					(pts
						(arc
							(start -0.3302 -0.4318)
							(mid -0.402042 -0.402042)
							(end -0.4318 -0.3302)
						)
						(arc
							(start -0.4318 0.3302)
							(mid -0.402042 0.402042)
							(end -0.3302 0.4318)
						)
						(arc
							(start 0.3302 0.4318)
							(mid 0.402042 0.402042)
							(end 0.4318 0.3302)
						)
						(arc
							(start 0.4318 -0.3302)
							(mid 0.402042 -0.402042)
							(end 0.3302 -0.4318)
						)
					)
					(width 0)
					(fill yes)
				)
			)
		)
	)
	(footprint ""
		(layer "F.Cu")
		(at 197.485 -164.846 -90)
		(property "Reference" "R579"
			(at 0 0 270)
			(layer "F.SilkS")
			(hide yes)
			(effects
				(font
					(size 1.27 1.27)
				)
			)
		)
		(property "Value" "0R2J-2-GP"
			(at 0.064008 -3.993896 270)
			(unlocked yes)
			(layer "F.Fab")
			(hide yes)
			(effects
				(font
					(size 1.016 1.016)
					(thickness 0.1524)
				)
			)
		)
		(property "Device Type" "R402H16"
			(at 0.064008 -5.517896 270)
			(unlocked yes)
			(layer "F.Fab")
			(hide yes)
			(effects
				(font
					(size 1.016 1.016)
					(thickness 0.1524)
				)
			)
		)
		(duplicate_pad_numbers_are_jumpers no)
		(fp_line
			(start -0.508 -0.9398)
			(end -0.508 0.9398)
			(stroke
				(width 0.1524)
				(type default)
			)
			(layer "F.SilkS")
		)
		(fp_line
			(start 0.508 -0.9398)
			(end -0.508 -0.9398)
			(stroke
				(width 0.1524)
				(type default)
			)
			(layer "F.SilkS")
		)
		(fp_rect
			(start -0.508 0.9398)
			(end 0.508 -0.9398)
			(stroke
				(width 0)
				(type default)
			)
			(fill no)
			(layer "F.CrtYd")
		)
		(fp_rect
			(start -0.508 0.9398)
			(end 0.508 -0.9398)
			(stroke
				(width 0)
				(type default)
			)
			(fill no)
			(layer "F.Fab")
		)
		(pad "1" smd custom
			(at 0 -0.4445 270)
			(size 0.1397 0.1397)
			(layers "F.Cu" "F.Mask" "F.Paste")
			(net "P3V3_PG")
			(options
				(clearance outline)
				(anchor circle)
			)
			(primitives
				(gr_poly
					(pts
						(arc
							(start -0.1778 -0.2794)
							(mid -0.249642 -0.249642)
							(end -0.2794 -0.1778)
						)
						(arc
							(start -0.2794 0.1778)
							(mid -0.249642 0.249642)
							(end -0.1778 0.2794)
						)
						(arc
							(start 0.1778 0.2794)
							(mid 0.249642 0.249642)
							(end 0.2794 0.1778)
						)
						(arc
							(start 0.2794 -0.1778)
							(mid 0.249642 -0.249642)
							(end 0.1778 -0.2794)
						)
					)
					(width 0)
					(fill yes)
				)
			)
		)
		(pad "2" smd custom
			(at 0 0.4445 270)
			(size 0.1397 0.1397)
			(layers "F.Cu" "F.Mask" "F.Paste")
			(net "P3V3_PG_R")
			(options
				(clearance outline)
				(anchor circle)
			)
			(primitives
				(gr_poly
					(pts
						(arc
							(start -0.1778 -0.2794)
							(mid -0.249642 -0.249642)
							(end -0.2794 -0.1778)
						)
						(arc
							(start -0.2794 0.1778)
							(mid -0.249642 0.249642)
							(end -0.1778 0.2794)
						)
						(arc
							(start 0.1778 0.2794)
							(mid 0.249642 0.249642)
							(end 0.2794 0.1778)
						)
						(arc
							(start 0.2794 -0.1778)
							(mid 0.249642 -0.249642)
							(end 0.1778 -0.2794)
						)
					)
					(width 0)
					(fill yes)
				)
			)
		)
	)
)
